FILE_TYPE = CONNECTIVITY;
{Allegro Design Entry HDL 16.6-p007 (v16-6-112F) 10/10/2012}
"PAGE_NUMBER" = 16;
0"NC";
END.
